# T6G (Grand Teton) — schematic netlist excerpt (pin names and nets, part order shuffled) for the footprints in the layout excerpt that follows; sources: Cadence DE-HDL packaged netlist, KiCad conversion of 04192023_DAF0TMB3IC0_F0TG_MB_C_brd_V02_OCP.brd

C353  Q_CAP  1UF 4V 20% X6S  pkg 0201  page 334 : A = P0V9_CPU1_RT1_2A ; B = GND
PC295_4  Q_CAP  22UF 16V 20% X6S  pkg C0805  page 212 : A = SW_P12V_AUX_PVDDCR_CPU0_P1_FLT ; B = GND
R8234  Q_RES  33 5% CHIP  pkg 0402LF  page 217 : A = PWRGD_PVDDCR_CPU1_P1 ; B = PWRGD_PVDDCR_CPU1_P1_R

(kicad_pcb
	(version 20260206)
	(generator "pcbnew")
	(generator_version "10.0")
	(general
		(thickness 1.6)
		(legacy_teardrops no)
	)
	(paper "A4")
	(title_block
		(title "04192023_DAF0TMB3IC0_F0TG_MB_C_brd_V02_OCP.brd")
		(comment 1 "Grand Teton / footprints 8249-8251 of 8354")
	)
	(layers
		(0 "F.Cu" signal "TOP")
		(4 "In1.Cu" signal "GND")
		(6 "In2.Cu" signal "IN1")
		(8 "In3.Cu" signal "GND1")
		(10 "In4.Cu" signal "IN2")
		(12 "In5.Cu" signal "GND2")
		(14 "In6.Cu" signal "IN3")
		(16 "In7.Cu" signal "GND3")
		(18 "In8.Cu" signal "VCC")
		(20 "In9.Cu" signal "VCC1")
		(22 "In10.Cu" signal "GND4")
		(24 "In11.Cu" signal "IN4")
		(26 "In12.Cu" signal "GND5")
		(28 "In13.Cu" signal "IN5")
		(30 "In14.Cu" signal "GND6")
		(32 "In15.Cu" signal "IN6")
		(34 "In16.Cu" signal "GND7")
		(2 "B.Cu" signal "BOTTOM")
		(9 "F.Adhes" user "F.Adhesive")
		(11 "B.Adhes" user "B.Adhesive")
		(13 "F.Paste" user "Package Geometry/Pastemask Top")
		(15 "B.Paste" user "Package Geometry/Pastemask Bottom")
		(5 "F.SilkS" user "Ref Des/Silkscreen Top")
		(7 "B.SilkS" user "Ref Des/Silkscreen Bottom")
		(1 "F.Mask" user "Board Geometry/Soldermask Top")
		(3 "B.Mask" user "Board Geometry/Soldermask Bottom")
		(17 "Dwgs.User" user "User.Drawings")
		(19 "Cmts.User" user "User.Comments")
		(21 "Eco1.User" user "User.Eco1")
		(23 "Eco2.User" user "User.Eco2")
		(25 "Edge.Cuts" user "Board Geometry/Outline")
		(27 "Margin" user)
		(31 "F.CrtYd" user "Package Geometry/Place Bound Top")
		(29 "B.CrtYd" user "Package Geometry/Place Bound Bottom")
		(35 "F.Fab" user "Ref Des/Assembly Top")
		(33 "B.Fab" user "Ref Des/Assembly Bottom")
	)
	(footprint ""
		(layer "B.Cu")
		(at 24.765 -365.76 180)
		(property "Reference" "R8234"
			(at 0 0 0)
			(layer "B.SilkS")
			(hide yes)
			(effects
				(font
					(size 1.27 1.27)
				)
				(justify mirror)
			)
		)
		(property "Value" ""
			(at 0 0 0)
			(layer "B.Fab")
			(effects
				(font
					(size 1.27 1.27)
				)
				(justify mirror)
			)
		)
		(duplicate_pad_numbers_are_jumpers no)
		(fp_line
			(start 0.7874 0.4064)
			(end 0.7874 -0.4064)
			(stroke
				(width 0.1524)
				(type default)
			)
			(layer "B.SilkS")
		)
		(fp_line
			(start 0.7874 -0.4064)
			(end -0.7874 -0.4064)
			(stroke
				(width 0.1524)
				(type default)
			)
			(layer "B.SilkS")
		)
		(fp_line
			(start -0.7874 0.4064)
			(end 0.7874 0.4064)
			(stroke
				(width 0.1524)
				(type default)
			)
			(layer "B.SilkS")
		)
		(fp_line
			(start -0.7874 -0.4064)
			(end -0.7874 0.4064)
			(stroke
				(width 0.1524)
				(type default)
			)
			(layer "B.SilkS")
		)
		(fp_line
			(start 0.67945 0.3048)
			(end 0.67945 -0.305054)
			(stroke
				(width 0.1)
				(type default)
			)
			(layer "B.Fab")
		)
		(fp_line
			(start 0.67945 -0.305054)
			(end 0.12065 -0.305054)
			(stroke
				(width 0.1)
				(type default)
			)
			(layer "B.Fab")
		)
		(fp_line
			(start 0.12065 0.3048)
			(end 0.67945 0.3048)
			(stroke
				(width 0.1)
				(type default)
			)
			(layer "B.Fab")
		)
		(fp_line
			(start 0.12065 0.2794)
			(end 0.12065 0.3048)
			(stroke
				(width 0.1)
				(type default)
			)
			(layer "B.Fab")
		)
		(fp_line
			(start 0.12065 -0.2794)
			(end -0.12065 -0.2794)
			(stroke
				(width 0.1)
				(type default)
			)
			(layer "B.Fab")
		)
		(fp_line
			(start 0.12065 -0.305054)
			(end 0.12065 -0.2794)
			(stroke
				(width 0.1)
				(type default)
			)
			(layer "B.Fab")
		)
		(fp_line
			(start -0.120396 0.3048)
			(end -0.120396 0.2794)
			(stroke
				(width 0.1)
				(type default)
			)
			(layer "B.Fab")
		)
		(fp_line
			(start -0.120396 0.2794)
			(end 0.12065 0.2794)
			(stroke
				(width 0.1)
				(type default)
			)
			(layer "B.Fab")
		)
		(fp_line
			(start -0.12065 -0.2794)
			(end -0.12065 -0.3048)
			(stroke
				(width 0.1)
				(type default)
			)
			(layer "B.Fab")
		)
		(fp_line
			(start -0.12065 -0.3048)
			(end -0.67945 -0.3048)
			(stroke
				(width 0.1)
				(type default)
			)
			(layer "B.Fab")
		)
		(fp_line
			(start -0.67945 0.3048)
			(end -0.120396 0.3048)
			(stroke
				(width 0.1)
				(type default)
			)
			(layer "B.Fab")
		)
		(fp_line
			(start -0.67945 -0.3048)
			(end -0.67945 0.3048)
			(stroke
				(width 0.1)
				(type default)
			)
			(layer "B.Fab")
		)
		(pad "1" smd circle
			(at 0.40005 0)
			(size 0 0)
			(layers "B.Cu" "B.Mask" "B.Paste")
			(net "PWRGD_PVDDCR_CPU1_P1")
		)
		(pad "2" smd circle
			(at -0.40005 0)
			(size 0 0)
			(layers "B.Cu" "B.Mask" "B.Paste")
			(net "PWRGD_PVDDCR_CPU1_P1_R")
		)
	)
	(footprint ""
		(layer "B.Cu")
		(at 106.184954 -174.340012 90)
		(property "Reference" "PC295_4"
			(at 0 0 90)
			(layer "B.SilkS")
			(hide yes)
			(effects
				(font
					(size 1.27 1.27)
				)
				(justify mirror)
			)
		)
		(property "Value" ""
			(at 0 0 90)
			(layer "B.Fab")
			(effects
				(font
					(size 1.27 1.27)
				)
				(justify mirror)
			)
		)
		(duplicate_pad_numbers_are_jumpers no)
		(fp_line
			(start 1.524 -0.762)
			(end -1.524 -0.762)
			(stroke
				(width 0.1524)
				(type default)
			)
			(layer "B.SilkS")
		)
		(fp_line
			(start -1.524 -0.762)
			(end -1.524 0.762)
			(stroke
				(width 0.1524)
				(type default)
			)
			(layer "B.SilkS")
		)
		(fp_line
			(start 1.524 0.762)
			(end 1.524 -0.762)
			(stroke
				(width 0.1524)
				(type default)
			)
			(layer "B.SilkS")
		)
		(fp_line
			(start -1.524 0.762)
			(end 1.524 0.762)
			(stroke
				(width 0.1524)
				(type default)
			)
			(layer "B.SilkS")
		)
		(fp_line
			(start 1.1049 -0.724916)
			(end 1.1049 0.724916)
			(stroke
				(width 0.1)
				(type default)
			)
			(layer "B.Fab")
		)
		(fp_line
			(start -1.1049 -0.724916)
			(end 1.1049 -0.724916)
			(stroke
				(width 0.1)
				(type default)
			)
			(layer "B.Fab")
		)
		(fp_line
			(start 1.1049 0.724916)
			(end -1.1049 0.724916)
			(stroke
				(width 0.1)
				(type default)
			)
			(layer "B.Fab")
		)
		(fp_line
			(start -1.1049 0.724916)
			(end -1.1049 -0.724916)
			(stroke
				(width 0.1)
				(type default)
			)
			(layer "B.Fab")
		)
		(pad "1" smd rect
			(at 0.889 0 90)
			(size 1.016 1.27)
			(layers "B.Cu" "B.Mask" "B.Paste")
			(net "SW_P12V_AUX_PVDDCR_CPU0_P1_FLT")
		)
		(pad "2" smd rect
			(at -0.889 0 90)
			(size 1.016 1.27)
			(layers "B.Cu" "B.Mask" "B.Paste")
			(net "GND")
		)
	)
	(footprint ""
		(layer "B.Cu")
		(at 99.111562 -386.766562 90)
		(property "Reference" "C353"
			(at 0 0 90)
			(layer "B.SilkS")
			(hide yes)
			(effects
				(font
					(size 1.27 1.27)
				)
				(justify mirror)
			)
		)
		(property "Value" ""
			(at 0 0 90)
			(layer "B.Fab")
			(effects
				(font
					(size 1.27 1.27)
				)
				(justify mirror)
			)
		)
		(duplicate_pad_numbers_are_jumpers no)
		(fp_line
			(start 0.299974 -0.150114)
			(end -0.299974 -0.150114)
			(stroke
				(width 0.1)
				(type default)
			)
			(layer "B.Fab")
		)
		(fp_line
			(start -0.299974 -0.150114)
			(end -0.299974 0.150114)
			(stroke
				(width 0.1)
				(type default)
			)
			(layer "B.Fab")
		)
		(fp_line
			(start 0.299974 0.150114)
			(end 0.299974 -0.150114)
			(stroke
				(width 0.1)
				(type default)
			)
			(layer "B.Fab")
		)
		(fp_line
			(start -0.299974 0.150114)
			(end 0.299974 0.150114)
			(stroke
				(width 0.1)
				(type default)
			)
			(layer "B.Fab")
		)
		(pad "1" smd rect
			(at 0.2667 0 270)
			(size 0.3048 0.381)
			(layers "B.Cu" "B.Mask" "B.Paste")
			(net "P0V9_CPU1_RT1_2A")
		)
		(pad "2" smd rect
			(at -0.2667 0 270)
			(size 0.3048 0.381)
			(layers "B.Cu" "B.Mask" "B.Paste")
			(net "GND")
		)
	)
)
